FILE_TYPE = CONNECTIVITY;
{Allegro Design Entry HDL 17.2-2016 S081 (4005846) 1/11/2022}
"PAGE_NUMBER" = 112;
0"NC";
1"GND\g";
2"GND\g";
3"GND\g";
4"GND\g";
5"GND\g";
6"GND\g";
7"GND\g";
8"GND\g";
9"GND\g";
10"GND\g";
11"GND\g";
12"GND\g";
13"GND\g";
14"GND\g";
15"GND\g";
16"GND\g";
17"GND\g";
18"GND\g";
19"P3V3\g";
20"P3V3\g";
21"GND\g";
22"P3V3\g";
23"GND\g";
24"P3V3\g";
25"GND\g";
26"P3V3\g";
27"P3V3\g";
28"P3V3_9ZX_VDD_3\g";
29"P3V3_9ZX_VDD_4\g";
30"SADR_3";
31"SADR_4";
32"P3V3\g";
33"GND\g";
34"P3V3_9ZX_VDDA_4\g";
35"FM_CLK_BUFFER3_EN";
36"SMB_CPU0_3_XLTR_SCL";
37"SMB_CPU0_3_XLTR_SDA";
38"FM_CLK_BUFFER4_EN";
39"FM_CLK_BUFFER4_EN";
40"P3V3_9ZX_VDDA_3\g";
41"SMB_CPU0_3_XLTR_SCL";
42"SMB_CPU0_3_XLTR_SDA";
43"FM_CLK_BUFFER3_EN";
44"P3V3_9ZX_VDD_4\g";
45"SMB_CLK_BUF3_SCL";
46"FM_CLK_BUFFER3_EN_R";
47"SMB_CLK_BUF4_SCL";
48"FM_CLK_BUFFER4_EN_R";
49"SMB_CLK_BUF4_SDA";
50"SMB_CLK_BUF3_SDA";
51"P3V3_9ZX_VDDA_4\g";
52"P3V3_9ZX_VDDA_3\g";
53"CLK_100M_CPU1_CLK11_DN";
54"CLK_100M_CPU1_CLK11_DP";
55"SADR_3";
56"SADR_4";
57"CLK_100M_CPU0_CLK11_DN";
58"CLK_100M_CPU0_CLK11_DP";
59"GND\g";
60"P3V3_9ZX_VDDA_4\g";
61"CLK_100M_E1S_3_R_DP";
62"CLK_100M_E1S_3_R_DN";
63"CLK_100M_E1S_4_R_DP";
64"CLK_100M_E1S_4_R_DN";
65"CLK_BUF_E1S_4_OE";
66"CLK_BUF_E1S_3_OE";
67"GND\g";
68"CLK_100M_E1S_4_DN";
69"CLK_100M_E1S_4_DP";
70"CLKBUF4_PLL_MODE";
71"GND\g";
72"CLK_100M_E1S_3_DN";
73"CLK_100M_E1S_3_DP";
74"FM_CLK_100M_M2_1_OE_N";
75"CLK_BUF_E1S_2_OE";
76"FM_CLK_100M_M2_2_OE_N";
77"P3V3_9ZX_VDD_3\g";
78"CLKBUF3_PLL_MODE";
79"P3V3_9ZX_VDDA_3\g";
80"CLK_100M_E1S_2_R_DP";
81"CLK_100M_M2_2_R_DN";
82"CLK_100M_M2_2_R_DP";
83"CLK_100M_M2_1_R_DN";
84"CLK_100M_M2_1_R_DP";
85"CLK_100M_E1S_2_R_DN";
86"CLK_100M_E1S_1_R_DN";
87"CLK_100M_E1S_1_R_DP";
88"CLK_BUF_E1S_1_OE";
89"CLK_100M_M2_1_DN";
90"CLK_100M_E1S_1_DP";
91"CLK_100M_E1S_2_DP";
92"CLK_100M_E1S_1_DN";
93"CLK_100M_E1S_2_DN";
94"CLK_100M_M2_1_DP";
95"CLK_100M_M2_2_DP";
96"CLK_100M_M2_2_DN";
97"GND\g";
98"GND\g";
%"9ZXL0451EKILFT"
"1","(-3200,4850)","0","pure_quanta","I1";
;
LOCATION"U72"
$SEC"1"
CDS_SEC"1"
PART_TYPE"SMLF"
MATERIAL"IC"
VALUE"9ZXL0451EKILFT"
PART_NUMBER"AL000451003"
NEEDS_NO_SIZE"TRUE"
CDS_LIB"pure_quanta"
CDS_LMAN_SYM_OUTLINE"-475,725,475,-725";
"VSADR0_TRI"
$PN"5"55;
"NC2"
$PN"17"0;
"NC3"
$PN"30"0;
"VDD0"
$PN"12"77;
"DIF3"
$PN"27"82;
"DIF1"
$PN"19"80;
"EPAD_GND"
$PN"33"21;
"^HIBW_BYPM_LOBW# \B"
$PN"32"78;
"VDD1"
$PN"16"77;
"VDDA"
$PN"31"79;
"NC0"
$PN"10"0;
"DIF3# \B"
$PN"28"81;
"DIF2# \B"
$PN"23"83;
"VOE2# \B"
$PN"24"74;
"DIF2"
$PN"22"84;
"DIF1# \B"
$PN"20"85;
"VOE1# \B"
$PN"18"75;
"DIF0"
$PN"13"87;
"DIF0# \B"
$PN"14"86;
"^CKPWRGD_PD# \B"
$PN"1"46;
"VDD2"
$PN"21"77;
"SMBCLK"
$PN"7"45;
"FBOUT_NC# \B"
$PN"8"0;
"NC1"
$PN"11"0;
"SMBDAT"
$PN"6"50;
"VOE3# \B"
$PN"26"76;
"VOE0# \B"
$PN"15"88;
"FBOUT_NC"
$PN"9"0;
"VDD4"
$PN"29"77;
"VDD3"
$PN"25"77;
"VDDR"
$PN"2"52;
"DIF_IN# \B"
$PN"4"57;
"DIF_IN"
$PN"3"58;
%"Q_RES"
"1","(-1525,5025)","0","pure_quanta","I100";
;
LOCATION"R2306"
$SEC"1"
CDS_SEC"1"
VALUE"0"
CDS_LIB"pure_quanta"
WATTAGE"1/16W"
MATERIAL"CHIP"
TOLERANCE"5%"
PART_NUMBER"CS00002JB38"
PACK_TYPE"0402LF";
"B"
$PN"2"91;
"A"
$PN"1"80;
%"Q_RES"
"1","(-1525,4975)","0","pure_quanta","I101";
;
LOCATION"R2307"
$SEC"1"
CDS_SEC"1"
VALUE"0"
CDS_LIB"pure_quanta"
WATTAGE"1/16W"
MATERIAL"CHIP"
TOLERANCE"5%"
PART_NUMBER"CS00002JB38"
PACK_TYPE"0402LF";
"B"
$PN"2"93;
"A"
$PN"1"85;
%"Q_RES"
"1","(-1525,4925)","0","pure_quanta","I102";
;
LOCATION"R2308"
$SEC"1"
CDS_SEC"1"
VALUE"0"
CDS_LIB"pure_quanta"
WATTAGE"1/16W"
MATERIAL"CHIP"
TOLERANCE"5%"
PART_NUMBER"CS00002JB38"
PACK_TYPE"0402LF";
"B"
$PN"2"94;
"A"
$PN"1"84;
%"Q_RES"
"1","(-1525,4875)","0","pure_quanta","I103";
;
LOCATION"R2309"
$SEC"1"
CDS_SEC"1"
VALUE"0"
CDS_LIB"pure_quanta"
WATTAGE"1/16W"
MATERIAL"CHIP"
TOLERANCE"5%"
PART_NUMBER"CS00002JB38"
PACK_TYPE"0402LF";
"B"
$PN"2"89;
"A"
$PN"1"83;
%"Q_RES"
"1","(-1525,5125)","0","pure_quanta","I104";
;
LOCATION"R2304"
$SEC"1"
CDS_SEC"1"
VALUE"0"
CDS_LIB"pure_quanta"
WATTAGE"1/16W"
MATERIAL"CHIP"
TOLERANCE"5%"
PART_NUMBER"CS00002JB38"
PACK_TYPE"0402LF";
"B"
$PN"2"90;
"A"
$PN"1"87;
%"Q_RES"
"1","(-1425,2075)","0","pure_quanta","I105";
;
LOCATION"R2301"
$SEC"1"
CDS_SEC"1"
VALUE"0"
CDS_LIB"pure_quanta"
WATTAGE"1/16W"
MATERIAL"CHIP"
TOLERANCE"5%"
PART_NUMBER"CS00002JB38"
PACK_TYPE"0402LF";
"B"
$PN"2"72;
"A"
$PN"1"62;
%"Q_RES"
"1","(-1425,2025)","0","pure_quanta","I106";
;
LOCATION"R2302"
$SEC"1"
CDS_SEC"1"
VALUE"0"
CDS_LIB"pure_quanta"
WATTAGE"1/16W"
MATERIAL"CHIP"
TOLERANCE"5%"
PART_NUMBER"CS00002JB38"
PACK_TYPE"0402LF";
"B"
$PN"2"69;
"A"
$PN"1"63;
%"Q_RES"
"1","(-1425,1975)","0","pure_quanta","I107";
;
LOCATION"R2303"
$SEC"1"
CDS_SEC"1"
VALUE"0"
CDS_LIB"pure_quanta"
WATTAGE"1/16W"
MATERIAL"CHIP"
TOLERANCE"5%"
PART_NUMBER"CS00002JB38"
PACK_TYPE"0402LF";
"B"
$PN"2"68;
"A"
$PN"1"64;
%"Q_RES"
"1","(-1425,2125)","0","pure_quanta","I110";
;
LOCATION"R2300"
$SEC"1"
CDS_SEC"1"
VALUE"0"
CDS_LIB"pure_quanta"
WATTAGE"1/16W"
MATERIAL"CHIP"
TOLERANCE"5%"
PART_NUMBER"CS00002JB38"
PACK_TYPE"0402LF";
"B"
$PN"2"73;
"A"
$PN"1"61;
%"UNIVERSAL_GND"
"1","(-8325,1275)","0","pure_quanta_power","I121";
;
HDL_POWER"GND"
CDS_LIB"pure_quanta_power";
"A"1;
%"Q_CAP"
"1","(-8325,1560)","0","pure_quanta","I122";
;
LOCATION"C67"
$SEC"1"
CDS_SEC"1"
MATERIAL"X6S"
TOLERANCE"10%"
VALUE"1UF"
VOLTAGE"25V"
PACK_TYPE"C0402"
CDS_LIB"pure_quanta"
PART_NUMBER"CH5104KEB02";
"B"
$PN"2"1;
"A"
$PN"1"29;
%"Q_CAP"
"1","(-7925,1525)","0","pure_quanta","I126";
;
LOCATION"C72"
$SEC"1"
CDS_SEC"1"
MATERIAL"X7R"
TOLERANCE"10%"
VALUE"0.1UF"
VOLTAGE"25V"
PACK_TYPE"0402"
CDS_LIB"pure_quanta"
PART_NUMBER"CH4104K1B00";
"B"
$PN"2"2;
"A"
$PN"1"29;
%"UNIVERSAL_GND"
"1","(-7925,1250)","0","pure_quanta_power","I127";
;
HDL_POWER"GND"
CDS_LIB"pure_quanta_power";
"A"2;
%"Q_CAP"
"1","(-7675,1525)","0","pure_quanta","I128";
;
LOCATION"C75"
$SEC"1"
CDS_SEC"1"
MATERIAL"X7R"
TOLERANCE"10%"
VALUE"0.1UF"
VOLTAGE"25V"
PACK_TYPE"0402"
CDS_LIB"pure_quanta"
PART_NUMBER"CH4104K1B00";
"B"
$PN"2"3;
"A"
$PN"1"29;
%"UNIVERSAL_GND"
"1","(-7675,1250)","0","pure_quanta_power","I129";
;
HDL_POWER"GND"
CDS_LIB"pure_quanta_power";
"A"3;
%"UNIVERSAL_GND"
"1","(-7450,1250)","0","pure_quanta_power","I130";
;
HDL_POWER"GND"
CDS_LIB"pure_quanta_power";
"A"4;
%"Q_CAP"
"1","(-7450,1525)","0","pure_quanta","I131";
;
LOCATION"C79"
$SEC"1"
CDS_SEC"1"
MATERIAL"X7R"
TOLERANCE"10%"
VALUE"0.1UF"
VOLTAGE"25V"
PACK_TYPE"0402"
CDS_LIB"pure_quanta"
PART_NUMBER"CH4104K1B00";
"B"
$PN"2"4;
"A"
$PN"1"29;
%"UNIVERSAL_GND"
"1","(-7220,1245)","0","pure_quanta_power","I137";
;
HDL_POWER"GND"
CDS_LIB"pure_quanta_power";
"A"5;
%"Q_CAP"
"1","(-7220,1520)","0","pure_quanta","I138";
;
LOCATION"C80"
$SEC"1"
CDS_SEC"1"
MATERIAL"X7R"
TOLERANCE"10%"
VALUE"0.1UF"
VOLTAGE"25V"
PACK_TYPE"0402"
CDS_LIB"pure_quanta"
PART_NUMBER"CH4104K1B00";
"B"
$PN"2"5;
"A"
$PN"1"29;
%"UNIVERSAL_GND"
"1","(-6990,1240)","0","pure_quanta_power","I139";
;
HDL_POWER"GND"
CDS_LIB"pure_quanta_power";
"A"6;
%"Q_CAP"
"1","(-6990,1515)","0","pure_quanta","I140";
;
LOCATION"C82"
$SEC"1"
CDS_SEC"1"
MATERIAL"X7R"
TOLERANCE"10%"
VALUE"0.1UF"
VOLTAGE"25V"
PACK_TYPE"0402"
CDS_LIB"pure_quanta"
PART_NUMBER"CH4104K1B00";
"B"
$PN"2"6;
"A"
$PN"1"29;
%"UNIVERSAL_POWER"
"1","(-8850,2350)","0","pure_quanta_power","I141";
;
HDL_POWER"P3V3"
CDS_LIB"pure_quanta_power";
"A"26;
%"Q_INDUCTOR"
"1","(-8500,2225)","0","pure_quanta","I142";
;
LOCATION"L119"
$SEC"1"
CDS_SEC"1"
MATERIAL"IND"
VALUE"330/2.5A"
PART_NUMBER"CX12S331000"
PACK_TYPE"SMLF"
CDS_LIB"pure_quanta"
NEEDS_NO_SIZE"TRUE";
"1"
$PN"1"26;
"2"
$PN"2"29;
%"UNIVERSAL_POWER"
"1","(-7175,2400)","0","pure_quanta_power","I143";
;
HDL_POWER"P3V3_9ZX_VDD_4"
CDS_LIB"pure_quanta_power"
BOM_COST"SYS_CLOCK"
VOLTAGE"3.3"
ROOM"DB2000_1_BCLK";
"A"29;
%"UNIVERSAL_POWER"
"1","(-9025,5575)","0","pure_quanta_power","I144";
;
HDL_POWER"P3V3"
CDS_LIB"pure_quanta_power";
"A"27;
%"UNIVERSAL_GND"
"1","(-8500,4500)","0","pure_quanta_power","I145";
;
HDL_POWER"GND"
CDS_LIB"pure_quanta_power";
"A"7;
%"Q_CAP"
"1","(-8500,4785)","0","pure_quanta","I146";
;
LOCATION"C66"
$SEC"1"
CDS_SEC"1"
MATERIAL"X6S"
TOLERANCE"10%"
VALUE"1UF"
VOLTAGE"25V"
PACK_TYPE"C0402"
CDS_LIB"pure_quanta"
PART_NUMBER"CH5104KEB02";
"B"
$PN"2"7;
"A"
$PN"1"28;
%"UNIVERSAL_GND"
"1","(-8100,4475)","0","pure_quanta_power","I147";
;
HDL_POWER"GND"
CDS_LIB"pure_quanta_power";
"A"8;
%"Q_CAP"
"1","(-8100,4750)","0","pure_quanta","I149";
;
LOCATION"C2361"
$SEC"1"
CDS_SEC"1"
MATERIAL"X7R"
TOLERANCE"10%"
VALUE"0.1UF"
VOLTAGE"25V"
PACK_TYPE"0402"
CDS_LIB"pure_quanta"
PART_NUMBER"CH4104K1B00";
"B"
$PN"2"8;
"A"
$PN"1"28;
%"Q_INDUCTOR"
"1","(-8675,5450)","0","pure_quanta","I151";
;
LOCATION"L118"
$SEC"1"
CDS_SEC"1"
MATERIAL"IND"
VALUE"330/2.5A"
PART_NUMBER"CX12S331000"
PACK_TYPE"SMLF"
CDS_LIB"pure_quanta"
NEEDS_NO_SIZE"TRUE";
"1"
$PN"1"27;
"2"
$PN"2"28;
%"UNIVERSAL_GND"
"1","(-7850,4475)","0","pure_quanta_power","I154";
;
HDL_POWER"GND"
CDS_LIB"pure_quanta_power";
"A"9;
%"UNIVERSAL_GND"
"1","(-7625,4475)","0","pure_quanta_power","I155";
;
HDL_POWER"GND"
CDS_LIB"pure_quanta_power";
"A"10;
%"Q_CAP"
"1","(-7850,4750)","0","pure_quanta","I156";
;
LOCATION"C74"
$SEC"1"
CDS_SEC"1"
MATERIAL"X7R"
TOLERANCE"10%"
VALUE"0.1UF"
VOLTAGE"25V"
PACK_TYPE"0402"
CDS_LIB"pure_quanta"
PART_NUMBER"CH4104K1B00";
"B"
$PN"2"9;
"A"
$PN"1"28;
%"Q_CAP"
"1","(-7625,4750)","0","pure_quanta","I158";
;
LOCATION"C77"
$SEC"1"
CDS_SEC"1"
MATERIAL"X7R"
TOLERANCE"10%"
VALUE"0.1UF"
VOLTAGE"25V"
PACK_TYPE"0402"
CDS_LIB"pure_quanta"
PART_NUMBER"CH4104K1B00";
"B"
$PN"2"10;
"A"
$PN"1"28;
%"UNIVERSAL_GND"
"1","(-7395,4470)","0","pure_quanta_power","I160";
;
HDL_POWER"GND"
CDS_LIB"pure_quanta_power";
"A"11;
%"UNIVERSAL_GND"
"1","(-7165,4465)","0","pure_quanta_power","I161";
;
HDL_POWER"GND"
CDS_LIB"pure_quanta_power";
"A"12;
%"Q_CAP"
"1","(-7395,4745)","0","pure_quanta","I162";
;
LOCATION"C2373"
$SEC"1"
CDS_SEC"1"
MATERIAL"X7R"
TOLERANCE"10%"
VALUE"0.1UF"
VOLTAGE"25V"
PACK_TYPE"0402"
CDS_LIB"pure_quanta"
PART_NUMBER"CH4104K1B00";
"B"
$PN"2"11;
"A"
$PN"1"28;
%"Q_CAP"
"1","(-7165,4740)","0","pure_quanta","I163";
;
LOCATION"C81"
$SEC"1"
CDS_SEC"1"
MATERIAL"X7R"
TOLERANCE"10%"
VALUE"0.1UF"
VOLTAGE"25V"
PACK_TYPE"0402"
CDS_LIB"pure_quanta"
PART_NUMBER"CH4104K1B00";
"B"
$PN"2"12;
"A"
$PN"1"28;
%"UNIVERSAL_POWER"
"1","(-7350,5625)","0","pure_quanta_power","I166";
;
HDL_POWER"P3V3_9ZX_VDD_3"
CDS_LIB"pure_quanta_power"
BOM_COST"SYS_CLOCK"
VOLTAGE"3.3"
ROOM"DB2000_1_BCLK";
"A"28;
%"Q_RES"
"1","(-7000,5425)","0","pure_quanta","I167";
;
LOCATION"R2298"
$SEC"1"
CDS_SEC"1"
WATTAGE"1/10W"
MATERIAL"CHIP"
TOLERANCE"1%"
VALUE"1"
PACK_TYPE"0603LF"
CDS_LIB"pure_quanta"
PART_NUMBER"CS-1003F920";
"B"
$PN"2"40;
"A"
$PN"1"28;
%"UNIVERSAL_GND"
"1","(-6325,1775)","0","pure_quanta_power","I172";
;
HDL_POWER"GND"
CDS_LIB"pure_quanta_power";
"A"13;
%"Q_CAP"
"1","(-6325,2050)","0","pure_quanta","I173";
;
LOCATION"C184"
$SEC"1"
CDS_SEC"1"
MATERIAL"X6S"
TOLERANCE"10%"
VALUE"1UF"
VOLTAGE"25V"
PACK_TYPE"C0402"
CDS_LIB"pure_quanta"
PART_NUMBER"CH5104KEB02";
"B"
$PN"2"13;
"A"
$PN"1"34;
%"UNIVERSAL_GND"
"1","(-6075,1775)","0","pure_quanta_power","I174";
;
HDL_POWER"GND"
CDS_LIB"pure_quanta_power";
"A"14;
%"Q_CAP"
"1","(-6075,2050)","0","pure_quanta","I175";
;
LOCATION"C186"
$SEC"1"
CDS_SEC"1"
MATERIAL"X7R"
TOLERANCE"10%"
VALUE"0.1UF"
VOLTAGE"25V"
PACK_TYPE"0402"
CDS_LIB"pure_quanta"
PART_NUMBER"CH4104K1B00";
"B"
$PN"2"14;
"A"
$PN"1"34;
%"UNIVERSAL_GND"
"1","(-5875,1775)","0","pure_quanta_power","I176";
;
HDL_POWER"GND"
CDS_LIB"pure_quanta_power";
"A"15;
%"Q_CAP"
"1","(-5875,2050)","0","pure_quanta","I177";
;
LOCATION"C2384"
$SEC"1"
CDS_SEC"1"
MATERIAL"X7R"
TOLERANCE"10%"
VALUE"0.1UF"
VOLTAGE"25V"
PACK_TYPE"0402"
CDS_LIB"pure_quanta"
PART_NUMBER"CH4104K1B00";
"B"
$PN"2"15;
"A"
$PN"1"34;
%"Q_RES"
"1","(-6825,2200)","0","pure_quanta","I178";
;
LOCATION"R2299"
$SEC"1"
CDS_SEC"1"
WATTAGE"1/10W"
MATERIAL"CHIP"
TOLERANCE"1%"
VALUE"1"
PACK_TYPE"0603LF"
CDS_LIB"pure_quanta"
PART_NUMBER"CS-1003F920";
"B"
$PN"2"34;
"A"
$PN"1"29;
%"VCC_CORE"
"1","(-5875,2400)","0","pure_quanta_power","I179";
;
HDL_POWER"P3V3_9ZX_VDDA_4"
CDS_LIB"pure_quanta_power"
BOM_COST"SYS_CLOCK"
VOLTAGE"3.3"
ROOM"DB2000_1_BCLK";
"A"34;
%"UNIVERSAL_GND"
"1","(-6200,5000)","0","pure_quanta_power","I180";
;
HDL_POWER"GND"
CDS_LIB"pure_quanta_power";
"A"16;
%"UNIVERSAL_GND"
"1","(-5950,5000)","0","pure_quanta_power","I181";
;
HDL_POWER"GND"
CDS_LIB"pure_quanta_power";
"A"17;
%"Q_CAP"
"1","(-6200,5275)","0","pure_quanta","I182";
;
LOCATION"C2379"
$SEC"1"
CDS_SEC"1"
MATERIAL"X6S"
TOLERANCE"10%"
VALUE"1UF"
VOLTAGE"25V"
PACK_TYPE"C0402"
CDS_LIB"pure_quanta"
PART_NUMBER"CH5104KEB02";
"B"
$PN"2"16;
"A"
$PN"1"40;
%"Q_CAP"
"1","(-5950,5275)","0","pure_quanta","I183";
;
LOCATION"C185"
$SEC"1"
CDS_SEC"1"
MATERIAL"X7R"
TOLERANCE"10%"
VALUE"0.1UF"
VOLTAGE"25V"
PACK_TYPE"0402"
CDS_LIB"pure_quanta"
PART_NUMBER"CH4104K1B00";
"B"
$PN"2"17;
"A"
$PN"1"40;
%"UNIVERSAL_GND"
"1","(-5750,5000)","0","pure_quanta_power","I184";
;
HDL_POWER"GND"
CDS_LIB"pure_quanta_power";
"A"18;
%"Q_CAP"
"1","(-5750,5275)","0","pure_quanta","I185";
;
LOCATION"C187"
$SEC"1"
CDS_SEC"1"
MATERIAL"X7R"
TOLERANCE"10%"
VALUE"0.1UF"
VOLTAGE"25V"
PACK_TYPE"0402"
CDS_LIB"pure_quanta"
PART_NUMBER"CH4104K1B00";
"B"
$PN"2"18;
"A"
$PN"1"40;
%"VCC_CORE"
"1","(-5750,5625)","0","pure_quanta_power","I186";
;
HDL_POWER"P3V3_9ZX_VDDA_3"
CDS_LIB"pure_quanta_power"
BOM_COST"SYS_CLOCK"
VOLTAGE"3.3"
ROOM"DB2000_1_BCLK";
"A"40;
%"UNIVERSAL_GND"
"1","(-1550,5275)","0","pure_quanta_power","I187";
;
HDL_POWER"GND"
CDS_LIB"pure_quanta_power";
"A"98;
%"UNIVERSAL_POWER"
"1","(-1550,5975)","0","pure_quanta_power","I188";
;
HDL_POWER"P3V3"
CDS_LIB"pure_quanta_power";
"A"19;
%"Q_RES"
"2","(-1550,5425)","0","pure_quanta","I189";
;
LOCATION"R126"
$SEC"1"
CDS_SEC"1"
WATTAGE"1/16W"
MATERIAL"CHIP"
TOLERANCE"5%"
VALUE"10K"
PACK_TYPE"0402LF"
CDS_LIB"pure_quanta"
PART_NUMBER"TMP_QCS31002JB28";
"A"
$PN"1"78;
"B"
$PN"2"98;
%"Q_RES"
"2","(-1550,5775)","0","pure_quanta","I190";
;
LOCATION"R125"
$SEC"1"
CDS_SEC"1"
WATTAGE"1/16W"
MATERIAL"CHIP"
TOLERANCE"5%"
VALUE"10K"
PACK_TYPE"0402LF"
CDS_LIB"pure_quanta"
PART_NUMBER"TMP_QCS31002JB28";
"A"
$PN"1"19;
"B"
$PN"2"78;
%"UNIVERSAL_GND"
"1","(-1525,2200)","0","pure_quanta_power","I191";
;
HDL_POWER"GND"
CDS_LIB"pure_quanta_power";
"A"97;
%"UNIVERSAL_POWER"
"1","(-1525,2900)","0","pure_quanta_power","I192";
;
HDL_POWER"P3V3"
CDS_LIB"pure_quanta_power";
"A"20;
%"Q_RES"
"2","(-1525,2350)","0","pure_quanta","I193";
;
LOCATION"R124"
$SEC"1"
CDS_SEC"1"
WATTAGE"1/16W"
MATERIAL"CHIP"
TOLERANCE"5%"
VALUE"10K"
PACK_TYPE"0402LF"
CDS_LIB"pure_quanta"
PART_NUMBER"TMP_QCS31002JB28";
"A"
$PN"1"70;
"B"
$PN"2"97;
%"Q_RES"
"2","(-1525,2700)","0","pure_quanta","I194";
;
LOCATION"R123"
$SEC"1"
CDS_SEC"1"
WATTAGE"1/16W"
MATERIAL"CHIP"
TOLERANCE"5%"
VALUE"10K"
PACK_TYPE"0402LF"
CDS_LIB"pure_quanta"
PART_NUMBER"TMP_QCS31002JB28";
"A"
$PN"1"20;
"B"
$PN"2"70;
%"UNIVERSAL_GND"
"1","(-2500,4025)","0","pure_quanta_power","I195";
;
HDL_POWER"GND"
CDS_LIB"pure_quanta_power";
"A"21;
%"UNIVERSAL_GND"
"1","(-2175,1000)","0","pure_quanta_power","I196";
;
HDL_POWER"GND"
CDS_LIB"pure_quanta_power";
"A"59;
%"Q_RES"
"2","(-8525,3250)","0","pure_quanta","I197";
;
LOCATION"R598"
$SEC"1"
CDS_SEC"1"
WATTAGE"1/16W"
MATERIAL"CHIP"
TOLERANCE"5%"
VALUE"1K"
PACK_TYPE"0402LF"
CDS_LIB"pure_quanta"
PART_NUMBER"TMP_QCS21002JB34";
"A"
$PN"1"30;
"B"
$PN"2"23;
%"UNIVERSAL_POWER"
"1","(-8525,3925)","0","pure_quanta_power","I199";
;
HDL_POWER"P3V3"
CDS_LIB"pure_quanta_power";
"A"22;
%"9ZXL0451EKILFT"
"1","(-2975,1850)","0","pure_quanta","I2";
;
LOCATION"U71"
$SEC"1"
CDS_SEC"1"
PART_TYPE"SMLF"
MATERIAL"IC"
VALUE"9ZXL0451EKILFT"
PART_NUMBER"AL000451003"
NEEDS_NO_SIZE"TRUE"
CDS_LIB"pure_quanta"
CDS_LMAN_SYM_OUTLINE"-475,725,475,-725";
"VSADR0_TRI"
$PN"5"56;
"NC2"
$PN"17"0;
"NC3"
$PN"30"0;
"VDD0"
$PN"12"44;
"DIF3"
$PN"27"0;
"DIF1"
$PN"19"63;
"EPAD_GND"
$PN"33"59;
"^HIBW_BYPM_LOBW# \B"
$PN"32"70;
"VDD1"
$PN"16"44;
"VDDA"
$PN"31"60;
"NC0"
$PN"10"0;
"DIF3# \B"
$PN"28"0;
"DIF2# \B"
$PN"23"0;
"VOE2# \B"
$PN"24"0;
"DIF2"
$PN"22"0;
"DIF1# \B"
$PN"20"64;
"VOE1# \B"
$PN"18"65;
"DIF0"
$PN"13"61;
"DIF0# \B"
$PN"14"62;
"^CKPWRGD_PD# \B"
$PN"1"48;
"VDD2"
$PN"21"44;
"SMBCLK"
$PN"7"47;
"FBOUT_NC# \B"
$PN"8"0;
"NC1"
$PN"11"0;
"SMBDAT"
$PN"6"49;
"VOE3# \B"
$PN"26"0;
"VOE0# \B"
$PN"15"66;
"FBOUT_NC"
$PN"9"0;
"VDD4"
$PN"29"44;
"VDD3"
$PN"25"44;
"VDDR"
$PN"2"51;
"DIF_IN# \B"
$PN"4"53;
"DIF_IN"
$PN"3"54;
%"UNIVERSAL_GND"
"1","(-8525,3075)","0","pure_quanta_power","I200";
;
CDS_LIB"pure_quanta_power"
HDL_POWER"GND";
"A"23;
%"UNIVERSAL_POWER"
"1","(-8275,3925)","0","pure_quanta_power","I201";
;
HDL_POWER"P3V3"
CDS_LIB"pure_quanta_power";
"A"24;
%"UNIVERSAL_GND"
"1","(-8275,3075)","0","pure_quanta_power","I204";
;
CDS_LIB"pure_quanta_power"
HDL_POWER"GND";
"A"25;
%"Q_RES"
"1","(-4675,4725)","0","pure_quanta","I211";
;
LOCATION"R629"
$SEC"1"
CDS_SEC"1"
VALUE"0"
CDS_LIB"pure_quanta"
WATTAGE"1/16W"
MATERIAL"CHIP"
TOLERANCE"5%"
PART_NUMBER"CS00002JB38"
PACK_TYPE"0402LF";
"B"
$PN"2"45;
"A"
$PN"1"41;
%"Q_RES"
"1","(-4675,4775)","0","pure_quanta","I212";
;
LOCATION"R628"
$SEC"1"
CDS_SEC"1"
VALUE"0"
CDS_LIB"pure_quanta"
WATTAGE"1/16W"
MATERIAL"CHIP"
TOLERANCE"5%"
PART_NUMBER"CS00002JB38"
PACK_TYPE"0402LF";
"B"
$PN"2"50;
"A"
$PN"1"42;
%"Q_RES"
"1","(-4450,1725)","0","pure_quanta","I215";
;
LOCATION"R631"
$SEC"1"
CDS_SEC"1"
VALUE"0"
CDS_LIB"pure_quanta"
WATTAGE"1/16W"
MATERIAL"CHIP"
TOLERANCE"5%"
PART_NUMBER"CS00002JB38"
PACK_TYPE"0402LF";
"B"
$PN"2"47;
"A"
$PN"1"36;
%"Q_RES"
"1","(-4450,1775)","0","pure_quanta","I216";
;
LOCATION"R630"
$SEC"1"
CDS_SEC"1"
VALUE"0"
CDS_LIB"pure_quanta"
WATTAGE"1/16W"
MATERIAL"CHIP"
TOLERANCE"5%"
PART_NUMBER"CS00002JB38"
PACK_TYPE"0402LF";
"B"
$PN"2"49;
"A"
$PN"1"37;
%"Q_RES"
"2","(-8525,3675)","0","pure_quanta","I217";
;
LOCATION"R627"
$SEC"1"
CDS_SEC"1"
WATTAGE"1/16W"
MATERIAL"CHIP"
TOLERANCE"5%"
VALUE"1K"
PACK_TYPE"0402LF"
CDS_LIB"pure_quanta"
PART_NUMBER"TMP_QCS21002JB34";
"A"
$PN"1"22;
"B"
$PN"2"30;
%"Q_RES"
"2","(-8275,3675)","0","pure_quanta","I219";
;
LOCATION"R611"
$SEC"1"
CDS_SEC"1"
WATTAGE"1/16W"
MATERIAL"CHIP"
TOLERANCE"5%"
VALUE"1K"
PACK_TYPE"0402LF"
CDS_LIB"pure_quanta"
PART_NUMBER"TMP_QCS21002JB34";
"A"
$PN"1"24;
"B"
$PN"2"31;
%"Q_RES"
"2","(-8275,3250)","0","pure_quanta","I220";
;
LOCATION"R609"
$SEC"1"
CDS_SEC"1"
WATTAGE"1/16W"
MATERIAL"EMPTY"
TOLERANCE"5%"
VALUE"1K"
PACK_TYPE"0402LF"
CDS_LIB"pure_quanta"
PART_NUMBER"TMP_QCS21002JB34";
"A"
$PN"1"31;
"B"
$PN"2"25;
%"Q_RES"
"1","(-1500,4075)","0","pure_quanta","I240";
;
LOCATION"R1247"
$SEC"1"
CDS_SEC"1"
MATERIAL"EMPTY"
VALUE"100"
CDS_LIB"pure_quanta"
WATTAGE"1/16W"
TOLERANCE"1%"
PART_NUMBER"TMP_QCS11002FB22"
PACK_TYPE"0402LF";
"B"
$PN"2"71;
"A"
$PN"1"75;
%"UNIVERSAL_GND"
"1","(-1125,3700)","0","pure_quanta_power","I241";
;
HDL_POWER"GND"
CDS_LIB"pure_quanta_power";
"A"71;
%"Q_RES"
"1","(-1500,4175)","0","pure_quanta","I242";
;
LOCATION"R1246"
$SEC"1"
CDS_SEC"1"
MATERIAL"EMPTY"
VALUE"100"
CDS_LIB"pure_quanta"
WATTAGE"1/16W"
TOLERANCE"1%"
PART_NUMBER"TMP_QCS11002FB22"
PACK_TYPE"0402LF";
"B"
$PN"2"71;
"A"
$PN"1"88;
%"Q_RES"
"1","(-1500,3975)","0","pure_quanta","I243";
;
LOCATION"R1248"
$SEC"1"
CDS_SEC"1"
MATERIAL"EMPTY"
VALUE"100"
CDS_LIB"pure_quanta"
WATTAGE"1/16W"
TOLERANCE"1%"
PART_NUMBER"TMP_QCS11002FB22"
PACK_TYPE"0402LF";
"B"
$PN"2"71;
"A"
$PN"1"74;
%"Q_RES"
"1","(-1400,1250)","0","pure_quanta","I250";
;
LOCATION"R1250"
$SEC"1"
CDS_SEC"1"
MATERIAL"EMPTY"
VALUE"100"
CDS_LIB"pure_quanta"
WATTAGE"1/16W"
TOLERANCE"1%"
PART_NUMBER"TMP_QCS11002FB22"
PACK_TYPE"0402LF";
"B"
$PN"2"67;
"A"
$PN"1"65;
%"Q_RES"
"1","(-1400,1350)","0","pure_quanta","I251";
;
LOCATION"R1249"
$SEC"1"
CDS_SEC"1"
MATERIAL"EMPTY"
VALUE"100"
CDS_LIB"pure_quanta"
WATTAGE"1/16W"
TOLERANCE"1%"
PART_NUMBER"TMP_QCS11002FB22"
PACK_TYPE"0402LF";
"B"
$PN"2"67;
"A"
$PN"1"66;
%"UNIVERSAL_GND"
"1","(-1175,1050)","0","pure_quanta_power","I253";
;
HDL_POWER"GND"
CDS_LIB"pure_quanta_power";
"A"67;
%"UNIVERSAL_GND"
"1","(-6250,3025)","0","pure_quanta_power","I254";
;
CDS_LIB"pure_quanta_power"
HDL_POWER"GND";
"A"33;
%"Q_RES"
"2","(-6250,3275)","0","pure_quanta","I255";
;
LOCATION"R1237"
$SEC"1"
CDS_SEC"1"
WATTAGE"1/16W"
MATERIAL"EMPTY"
TOLERANCE"1%"
VALUE"4.7K"
PACK_TYPE"0402LF"
CDS_LIB"pure_quanta"
PART_NUMBER"CS24702FB10";
"A"
$PN"1"35;
"B"
$PN"2"33;
%"Q_RES"
"2","(-6250,3675)","0","pure_quanta","I256";
;
LOCATION"R1236"
$SEC"1"
CDS_SEC"1"
WATTAGE"1/16W"
MATERIAL"EMPTY"
TOLERANCE"1%"
VALUE"4.7K"
PACK_TYPE"0402LF"
CDS_LIB"pure_quanta"
PART_NUMBER"CS24702FB10";
"A"
$PN"1"32;
"B"
$PN"2"35;
%"UNIVERSAL_POWER"
"1","(-6250,3925)","0","pure_quanta_power","I257";
;
HDL_POWER"P3V3"
CDS_LIB"pure_quanta_power";
"A"32;
%"Q_RES"
"2","(-6000,3275)","0","pure_quanta","I258";
;
LOCATION"R1239"
$SEC"1"
CDS_SEC"1"
WATTAGE"1/16W"
MATERIAL"EMPTY"
TOLERANCE"1%"
VALUE"4.7K"
PACK_TYPE"0402LF"
CDS_LIB"pure_quanta"
PART_NUMBER"CS24702FB10";
"A"
$PN"1"39;
"B"
$PN"2"33;
%"Q_RES"
"2","(-6000,3675)","0","pure_quanta","I259";
;
LOCATION"R1238"
$SEC"1"
CDS_SEC"1"
WATTAGE"1/16W"
MATERIAL"EMPTY"
TOLERANCE"1%"
VALUE"4.7K"
PACK_TYPE"0402LF"
CDS_LIB"pure_quanta"
PART_NUMBER"CS24702FB10";
"A"
$PN"1"32;
"B"
$PN"2"39;
%"Q_RES"
"1","(-4450,1625)","0","pure_quanta","I262";
;
LOCATION"R1241"
$SEC"1"
CDS_SEC"1"
VALUE"0"
CDS_LIB"pure_quanta"
WATTAGE"1/16W"
MATERIAL"CHIP"
TOLERANCE"5%"
PART_NUMBER"CS00002JB38"
PACK_TYPE"0402LF";
"B"
$PN"2"48;
"A"
$PN"1"38;
%"Q_RES"
"1","(-4675,4625)","0","pure_quanta","I264";
;
LOCATION"R1240"
$SEC"1"
CDS_SEC"1"
VALUE"0"
CDS_LIB"pure_quanta"
WATTAGE"1/16W"
MATERIAL"CHIP"
TOLERANCE"5%"
PART_NUMBER"CS00002JB38"
PACK_TYPE"0402LF";
"B"
$PN"2"46;
"A"
$PN"1"43;
%"Q_RES"
"1","(-1525,4775)","0","pure_quanta","I268";
;
LOCATION"R2297"
$SEC"1"
CDS_SEC"1"
VALUE"0"
CDS_LIB"pure_quanta"
WATTAGE"1/16W"
MATERIAL"CHIP"
TOLERANCE"5%"
PART_NUMBER"CS00002JB38"
PACK_TYPE"0402LF";
"B"
$PN"2"96;
"A"
$PN"1"81;
%"Q_RES"
"1","(-1525,4825)","0","pure_quanta","I269";
;
LOCATION"R2296"
$SEC"1"
CDS_SEC"1"
VALUE"0"
CDS_LIB"pure_quanta"
WATTAGE"1/16W"
MATERIAL"CHIP"
TOLERANCE"5%"
PART_NUMBER"CS00002JB38"
PACK_TYPE"0402LF";
"B"
$PN"2"95;
"A"
$PN"1"82;
%"Q_RES"
"1","(-1475,3875)","0","pure_quanta","I270";
;
LOCATION"R1234"
$SEC"1"
CDS_SEC"1"
MATERIAL"EMPTY"
VALUE"100"
CDS_LIB"pure_quanta"
WATTAGE"1/16W"
TOLERANCE"1%"
PART_NUMBER"TMP_QCS11002FB22"
PACK_TYPE"0402LF";
"B"
$PN"2"71;
"A"
$PN"1"76;
%"VCC_CORE"
"1","(-4450,5425)","0","pure_quanta_power","I3";
;
HDL_POWER"P3V3_9ZX_VDDA_3"
BOM_COST"SYS_CLOCK"
CDS_LIB"pure_quanta_power"
VOLTAGE"3.3"
ROOM"DB2000_1_BCLK";
"A"52;
%"UNIVERSAL_POWER"
"1","(-4050,5800)","0","pure_quanta_power","I4";
;
HDL_POWER"P3V3_9ZX_VDD_3"
BOM_COST"SYS_CLOCK"
CDS_LIB"pure_quanta_power"
VOLTAGE"3.3"
ROOM"DB2000_1_BCLK";
"A"77;
%"VCC_CORE"
"1","(-2450,5800)","0","pure_quanta_power","I5";
;
HDL_POWER"P3V3_9ZX_VDDA_3"
BOM_COST"SYS_CLOCK"
CDS_LIB"pure_quanta_power"
VOLTAGE"3.3"
ROOM"DB2000_1_BCLK";
"A"79;
%"VCC_CORE"
"1","(-4500,2350)","0","pure_quanta_power","I6";
;
HDL_POWER"P3V3_9ZX_VDDA_4"
CDS_LIB"pure_quanta_power"
BOM_COST"SYS_CLOCK"
VOLTAGE"3.3"
ROOM"DB2000_1_BCLK";
"A"51;
%"UNIVERSAL_POWER"
"1","(-4100,2725)","0","pure_quanta_power","I7";
;
HDL_POWER"P3V3_9ZX_VDD_4"
CDS_LIB"pure_quanta_power"
BOM_COST"SYS_CLOCK"
VOLTAGE"3.3"
ROOM"DB2000_1_BCLK";
"A"44;
%"VCC_CORE"
"1","(-2250,2750)","0","pure_quanta_power","I8";
;
HDL_POWER"P3V3_9ZX_VDDA_4"
BOM_COST"SYS_CLOCK"
CDS_LIB"pure_quanta_power"
VOLTAGE"3.3"
ROOM"DB2000_1_BCLK";
"A"60;
%"Q_RES"
"1","(-1525,5075)","0","pure_quanta","I99";
;
LOCATION"R2305"
$SEC"1"
CDS_SEC"1"
VALUE"0"
CDS_LIB"pure_quanta"
WATTAGE"1/16W"
MATERIAL"CHIP"
TOLERANCE"5%"
PART_NUMBER"CS00002JB38"
PACK_TYPE"0402LF";
"B"
$PN"2"92;
"A"
$PN"1"86;
END.
